# S9S_MB_2U (Grand Teton) — schematic netlist excerpt (pin names and nets, part order shuffled) for the footprints in the layout excerpt that follows; sources: Cadence DE-HDL packaged netlist, KiCad conversion of 03242023_DA0F0TMBIJ0_F0T_Motherboard_J_brd_V01_OCP.brd

J28  SCONN288_ADR50017P087CC  SCONN288_ADR50017-P087CC IO  pkg DDR288S_1-1VXB  page 109
  VIN_BULK0  = P12V_S3_AUX_CPU1_NVDIMM
  RFU0  = TP_CHF_CPU1_DIMM2_FRU_0
  VIN_MGMT  = P3V3_AUX
  HSCL  = I3C_SPD_DDREFGH_CPU1_LVC1_SCL_3
  HSDA  = I3C_SPD_DDREFGH_CPU1_LVC1_SDA
  VSS0  = GND
  DQ0_A  = M_F_CPU1_SA_DQ<0>
  VSS1  = GND
  DQ1_A  = M_F_CPU1_SA_DQ<1>
  VSS2  = GND
  DQS0_A_T  = M_F_CPU1_SA_DQS_DP<0>
  DQS0_A_C  = M_F_CPU1_SA_DQS_DN<0>
  VSS3  = GND
  DQ4_A  = M_F_CPU1_SA_DQ<4>
  VSS4  = GND
  DQ5_A  = M_F_CPU1_SA_DQ<5>
  VSS5  = GND
  DQ8_A  = M_F_CPU1_SA_DQ<8>
  VSS6  = GND
  DQ9_A  = M_F_CPU1_SA_DQ<9>
  VSS7  = GND
  DQS1_A_T  = M_F_CPU1_SA_DQS_DP<1>
  DQS1_A_C  = M_F_CPU1_SA_DQS_DN<1>
  VSS8  = GND
  DQ12_A  = M_F_CPU1_SA_DQ<12>
  VSS9  = GND
  DQ13_A  = M_F_CPU1_SA_DQ<13>
  VSS10  = GND
  DQ16_A  = M_F_CPU1_SA_DQ<16>
  VSS11  = GND
  DQ17_A  = M_F_CPU1_SA_DQ<17>
  VSS12  = GND
  DQS2_A_T  = M_F_CPU1_SA_DQS_DP<2>
  DQS2_A_C  = M_F_CPU1_SA_DQS_DN<2>
  VSS13  = GND
  DQ20_A  = M_F_CPU1_SA_DQ<20>
  VSS14  = GND
  DQ21_A  = M_F_CPU1_SA_DQ<21>
  VSS15  = GND
  DQ24_A  = M_F_CPU1_SA_DQ<24>
  VSS16  = GND
  DQ25_A  = M_F_CPU1_SA_DQ<25>
  VSS17  = GND
  DQS3_A_T  = M_F_CPU1_SA_DQS_DP<3>
  DQS3_A_C  = M_F_CPU1_SA_DQS_DN<3>
  VSS18  = GND
  DQ28_A  = M_F_CPU1_SA_DQ<28>
  VSS19  = GND
  DQ29_A  = M_F_CPU1_SA_DQ<29>
  VSS20  = GND
  CB0_A  = M_F_CPU1_SA_CB<0>
  VSS21  = GND
  CB1_A  = M_F_CPU1_SA_CB<1>
  VSS22  = GND
  DQS4_A_T  = M_F_CPU1_SA_DQS_DP<4>
  DQS4_A_C  = M_F_CPU1_SA_DQS_DN<4>
  VSS23  = GND
  CB4_A  = M_F_CPU1_SA_CB<4>
  VSS24  = GND
  CB5_A  = M_F_CPU1_SA_CB<5>
  VSS25  = GND
  ALERT_N  = M_F_CPU1_ALERT_N
  VSS26  = GND
  CS0_A_N  = M_F_CPU1_SA_CS_N<2>
  VSS27  = GND
  CA0_A  = M_F_CPU1_SA_CA<0>
  VSS28  = GND
  CA2_A  = M_F_CPU1_SA_CA<2>
  VSS29  = GND
  CA4_A  = M_F_CPU1_SA_CA<4>
  VSS30  = GND
  CA6_A  = M_F_CPU1_SA_CA<6>
  VSS31  = GND
  PAR_A  = M_F_CPU1_SA_PAR
  VSS32  = GND
  CA0_B  = M_F_CPU1_SB_CA<0>
  VSS33  = GND
  CA2_B  = M_F_CPU1_SB_CA<2>
  VSS34  = GND
  CA4_B  = M_F_CPU1_SB_CA<4>
  VSS35  = GND
  CA6_B  = M_F_CPU1_SB_CA<6>
  VSS36  = GND
  CS0_B_N  = M_F_CPU1_SB_CS_N<2>
  VSS37  = GND
  \lbd||rsp_a_n\  = M_F_CPU1_SA_RSP<1>
  \lbs||rsp_b_n\  = M_F_CPU1_SB_RSP<1>
  VSS38  = GND
  CB4_B  = M_F_CPU1_SB_CB<4>
  VSS39  = GND
  CB5_B  = M_F_CPU1_SB_CB<5>
  VSS40  = GND
  \dqs9_b_t||tdqs9_b_t||dbi4_b_n\  = M_F_CPU1_SB_DQS_DP<9>
  \dqs9_b_c||tdqs9_b_c\  = M_F_CPU1_SB_DQS_DN<9>
  VSS41  = GND
  CB0_B  = M_F_CPU1_SB_CB<0>
  VSS42  = GND
  CB1_B  = M_F_CPU1_SB_CB<1>
  VSS43  = GND
  DQ0_B  = M_F_CPU1_SB_DQ<0>
  VSS44  = GND
  DQ1_B  = M_F_CPU1_SB_DQ<1>
  VSS45  = GND
  DQS0_B_T  = M_F_CPU1_SB_DQS_DP<0>
  DQS0_B_C  = M_F_CPU1_SB_DQS_DN<0>
  VSS46  = GND
  DQ4_B  = M_F_CPU1_SB_DQ<4>
  VSS47  = GND
  DQ5_B  = M_F_CPU1_SB_DQ<5>
  VSS48  = GND
  DQ8_B  = M_F_CPU1_SB_DQ<8>
  VSS49  = GND
  DQ9_B  = M_F_CPU1_SB_DQ<9>
  VSS50  = GND
  DQS1_B_T  = M_F_CPU1_SB_DQS_DP<1>
  DQS1_B_C  = M_F_CPU1_SB_DQS_DN<1>
  VSS51  = GND
  DQ12_B  = M_F_CPU1_SB_DQ<12>
  VSS52  = GND
  DQ13_B  = M_F_CPU1_SB_DQ<13>
  VSS53  = GND
  DQ16_B  = M_F_CPU1_SB_DQ<16>
  VSS54  = GND
  DQ17_B  = M_F_CPU1_SB_DQ<17>
  VSS55  = GND
  DQS2_B_T  = M_F_CPU1_SB_DQS_DP<2>
  DQS2_B_C  = M_F_CPU1_SB_DQS_DN<2>
  VSS56  = GND
  DQ20_B  = M_F_CPU1_SB_DQ<20>
  VSS57  = GND
  DQ21_B  = M_F_CPU1_SB_DQ<21>
  VSS58  = GND
  DQ24_B  = M_F_CPU1_SB_DQ<24>
  VSS59  = GND
  DQ25_B  = M_F_CPU1_SB_DQ<25>
  VSS60  = GND
  DQS3_B_T  = M_F_CPU1_SB_DQS_DP<3>
  DQS3_B_C  = M_F_CPU1_SB_DQS_DN<3>
  VSS61  = GND
  DQ28_B  = M_F_CPU1_SB_DQ<28>
  VSS62  = GND
  DQ29_B  = M_F_CPU1_SB_DQ<29>
  VSS63  = GND
  RFU1  = TP_CHF_CPU1_DIMM2_FRU_1
  VIN_BULK1  = P12V_S3_AUX_CPU1_NVDIMM
  VIN_BULK2  = P12V_S3_AUX_CPU1_NVDIMM
  \pwr_good||fail_n\  = PWRGD_CHF_CPU1_DIMM2
  HSA  = PD_CHF_CPU1_DIMM2_SAA
  RFU2  = TP_CHF_CPU1_DIMM2_FRU_2
  RFU3  = TP_CHF_CPU1_DIMM2_FRU_3
  VSS64  = GND
  DQ2_A  = M_F_CPU1_SA_DQ<2>
  VSS65  = GND
  DQ3_A  = M_F_CPU1_SA_DQ<3>
  VSS66  = GND
  \dqs5_a_c||tdqs5_a_c||dqs5_a_t||tdqs5_a_t\  = M_F_CPU1_SA_DQS_DN<5>
  \dqs5_a_t||tdqs5_a_t\  = M_F_CPU1_SA_DQS_DP<5>
  VSS67  = GND
  DQ6_A  = M_F_CPU1_SA_DQ<6>
  VSS68  = GND
  DQ7_A  = M_F_CPU1_SA_DQ<7>
  VSS69  = GND
  DQ10_A  = M_F_CPU1_SA_DQ<10>
  VSS70  = GND
  DQ11_A  = M_F_CPU1_SA_DQ<11>
  VSS71  = GND
  \dqs6_a_c||tdqs6_a_c||dqs6_a_t||tdqs6_a_t\  = M_F_CPU1_SA_DQS_DN<6>
  \dqs6_a_t||tdqs6_a_t\  = M_F_CPU1_SA_DQS_DP<6>
  VSS72  = GND
  DQ14_A  = M_F_CPU1_SA_DQ<14>
  VSS73  = GND
  DQ15_A  = M_F_CPU1_SA_DQ<15>
  VSS74  = GND
  DQ18_A  = M_F_CPU1_SA_DQ<18>
  VSS75  = GND
  DQ19_A  = M_F_CPU1_SA_DQ<19>
  VSS76  = GND
  \dqs7_a_c||tdqs7_a_c\  = M_F_CPU1_SA_DQS_DN<7>
  \dqs7_a_t||tdqs7_a_t\  = M_F_CPU1_SA_DQS_DP<7>
  VSS77  = GND
  DQ22_A  = M_F_CPU1_SA_DQ<22>
  VSS78  = GND
  DQ23_A  = M_F_CPU1_SA_DQ<23>
  VSS79  = GND
  DQ26_A  = M_F_CPU1_SA_DQ<26>
  VSS80  = GND
  DQ27_A  = M_F_CPU1_SA_DQ<27>
  VSS81  = GND
  \dqs8_a_c||tdqs8_a_c\  = M_F_CPU1_SA_DQS_DN<8>
  \dqs8_a_t||tdqs8_a_t\  = M_F_CPU1_SA_DQS_DP<8>
  VSS82  = GND
  DQ30_A  = M_F_CPU1_SA_DQ<30>
  VSS83  = GND
  DQ31_A  = M_F_CPU1_SA_DQ<31>
  VSS84  = GND
  CB2_A  = M_F_CPU1_SA_CB<2>
  VSS85  = GND
  CB3_A  = M_F_CPU1_SA_CB<3>
  VSS86  = GND
  \dqs9_a_c||tdqs9_a_c\  = M_F_CPU1_SA_DQS_DN<9>
  \dqs9_a_t||tdqs9_a_t\  = M_F_CPU1_SA_DQS_DP<9>
  VSS87  = GND
  CB6_A  = M_F_CPU1_SA_CB<6>
  VSS88  = GND
  CB7_A  = M_F_CPU1_SA_CB<7>
  VSS89  = GND
  RESET_N  = RST_M_EF_CPU1_FPGA_N
  VSS90  = GND
  CS1_A_N  = M_F_CPU1_SA_CS_N<3>
  VSS91  = GND
  CA1_A  = M_F_CPU1_SA_CA<1>
  VSS92  = GND
  CA3_A  = M_F_CPU1_SA_CA<3>
  VSS93  = GND
  CA5_A  = M_F_CPU1_SA_CA<5>
  VSS94  = GND
  CK_T  = M_F_CPU1_CLK_DP<1>
  CK_C  = M_F_CPU1_CLK_DN<1>
  VSS95  = GND
  RFU4  = TP_CHF_CPU1_DIMM2_FRU_4
  CA1_B  = M_F_CPU1_SB_CA<1>
  VSS96  = GND
  CA3_B  = M_F_CPU1_SB_CA<3>
  VSS97  = GND
  CA5_B  = M_F_CPU1_SB_CA<5>
  VSS98  = GND
  PAR_B  = M_F_CPU1_SB_PAR
  VSS99  = GND
  CS1_B_N  = M_F_CPU1_SB_CS_N<3>
  VSS100  = GND
  RFU5  = TP_CHF_CPU1_DIMM2_FRU_5
  RFU6  = TP_CHF_CPU1_DIMM2_FRU_6
  VSS101  = GND
  CB6_B  = M_F_CPU1_SB_CB<6>
  VSS102  = GND
  CB7_B  = M_F_CPU1_SB_CB<7>
  VSS103  = GND
  DQS4_B_C  = M_F_CPU1_SB_DQS_DN<4>
  DQS4_B_T  = M_F_CPU1_SB_DQS_DP<4>
  VSS104  = GND
  CB2_B  = M_F_CPU1_SB_CB<2>
  VSS105  = GND
  CB3_B  = M_F_CPU1_SB_CB<3>
  VSS106  = GND
  DQ2_B  = M_F_CPU1_SB_DQ<2>
  VSS107  = GND
  DQ3_B  = M_F_CPU1_SB_DQ<3>
  VSS108  = GND
  \dqs5_b_c||tdqs5_b_c\  = M_F_CPU1_SB_DQS_DN<5>
  \dqs5_b_t||tdqs5_b_t\  = M_F_CPU1_SB_DQS_DP<5>
  VSS109  = GND
  DQ6_B  = M_F_CPU1_SB_DQ<6>
  VSS110  = GND
  DQ7_B  = M_F_CPU1_SB_DQ<7>
  VSS111  = GND
  DQ10_B  = M_F_CPU1_SB_DQ<10>
  VSS112  = GND
  DQ11_B  = M_F_CPU1_SB_DQ<11>
  VSS113  = GND
  \dqs6_b_c||tdqs6_b_c\  = M_F_CPU1_SB_DQS_DN<6>
  \dqs6_b_t||tdqs6_b_t\  = M_F_CPU1_SB_DQS_DP<6>
  VSS114  = GND
  DQ14_B  = M_F_CPU1_SB_DQ<14>
  VSS115  = GND
  DQ15_B  = M_F_CPU1_SB_DQ<15>
  VSS116  = GND
  DQ18_B  = M_F_CPU1_SB_DQ<18>
  VSS117  = GND
  DQ19_B  = M_F_CPU1_SB_DQ<19>
  VSS118  = GND
  \dqs7_b_c||tdqs7_b_c\  = M_F_CPU1_SB_DQS_DN<7>
  \dqs7_b_t||tdqs7_b_t\  = M_F_CPU1_SB_DQS_DP<7>
  VSS119  = GND
  DQ22_B  = M_F_CPU1_SB_DQ<22>
  VSS120  = GND
  DQ23_B  = M_F_CPU1_SB_DQ<23>
  VSS121  = GND
  DQ26_B  = M_F_CPU1_SB_DQ<26>
  VSS122  = GND
  DQ27_B  = M_F_CPU1_SB_DQ<27>
  VSS123  = GND
  \dqs8_b_c||tdqs8_b_c\  = M_F_CPU1_SB_DQS_DN<8>
  \dqs8_b_t||tdqs8_b_t\  = M_F_CPU1_SB_DQS_DP<8>
  VSS124  = GND
  DQ30_B  = M_F_CPU1_SB_DQ<30>
  VSS125  = GND
  DQ31_B  = M_F_CPU1_SB_DQ<31>
  VSS126  = GND
  G1  = GND
  G2  = GND
  G3  = GND

(kicad_pcb
	(version 20260206)
	(generator "pcbnew")
	(generator_version "10.0")
	(general
		(thickness 1.6)
		(legacy_teardrops no)
	)
	(paper "A4")
	(title_block
		(title "03242023_DA0F0TMBIJ0_F0T_Motherboard_J_brd_V01_OCP.brd")
		(comment 1 "Grand Teton / footprint 3431 of 6105 (J28), pads 229-274 of 291")
	)
	(layers
		(0 "F.Cu" signal "TOP")
		(4 "In1.Cu" signal "GND")
		(6 "In2.Cu" signal "IN1")
		(8 "In3.Cu" signal "GND1")
		(10 "In4.Cu" signal "IN2")
		(12 "In5.Cu" signal "GND2")
		(14 "In6.Cu" signal "IN3")
		(16 "In7.Cu" signal "GND3")
		(18 "In8.Cu" signal "VCC")
		(20 "In9.Cu" signal "VCC1")
		(22 "In10.Cu" signal "GND4")
		(24 "In11.Cu" signal "IN4")
		(26 "In12.Cu" signal "GND5")
		(28 "In13.Cu" signal "IN5")
		(30 "In14.Cu" signal "GND6")
		(32 "In15.Cu" signal "IN6")
		(34 "In16.Cu" signal "GND7")
		(2 "B.Cu" signal "BOTTOM")
		(9 "F.Adhes" user "F.Adhesive")
		(11 "B.Adhes" user "B.Adhesive")
		(13 "F.Paste" user "Package Geometry/Pastemask Top")
		(15 "B.Paste" user "Package Geometry/Pastemask Bottom")
		(5 "F.SilkS" user "Ref Des/Silkscreen Top")
		(7 "B.SilkS" user "Ref Des/Silkscreen Bottom")
		(1 "F.Mask" user "Board Geometry/Soldermask Top")
		(3 "B.Mask" user "Board Geometry/Soldermask Bottom")
		(17 "Dwgs.User" user "User.Drawings")
		(19 "Cmts.User" user "User.Comments")
		(21 "Eco1.User" user "User.Eco1")
		(23 "Eco2.User" user "User.Eco2")
		(25 "Edge.Cuts" user "Board Geometry/Outline")
		(27 "Margin" user)
		(31 "F.CrtYd" user "Package Geometry/Place Bound Top")
		(29 "B.CrtYd" user "Package Geometry/Place Bound Bottom")
		(35 "F.Fab" user "Ref Des/Assembly Top")
		(33 "B.Fab" user "Ref Des/Assembly Bottom")
	)
	(footprint ""
		(layer "F.Cu")
		(at 175.95088 -258.091686)
		(property "Reference" "J28"
			(at -0.26924 -81.680812 0)
			(unlocked yes)
			(layer "F.SilkS")
			(effects
				(font
					(size 0.7874 0.5842)
					(thickness 0.1524)
				)
				(justify left)
			)
		)
		(property "Value" ""
			(at 0 0 0)
			(layer "F.Fab")
			(effects
				(font
					(size 1.27 1.27)
				)
			)
		)
		(duplicate_pad_numbers_are_jumpers no)
		(pad "229" smd rect
			(at 2.050034 13.17498 270)
			(size 0.519938 1.4986)
			(layers "F.Cu" "F.Mask" "F.Paste")
			(net "M_F_CPU1_SB_CS_N<3>")
		)
		(pad "230" smd rect
			(at 2.050034 14.025118 270)
			(size 0.519938 1.4986)
			(layers "F.Cu" "F.Mask" "F.Paste")
			(net "GND")
		)
		(pad "231" smd rect
			(at 2.050034 14.875002 270)
			(size 0.519938 1.4986)
			(layers "F.Cu" "F.Mask" "F.Paste")
			(net "TP_CHF_CPU1_DIMM2_FRU_5")
		)
		(pad "232" smd rect
			(at 2.050034 15.724886 270)
			(size 0.519938 1.4986)
			(layers "F.Cu" "F.Mask" "F.Paste")
			(net "TP_CHF_CPU1_DIMM2_FRU_6")
		)
		(pad "233" smd rect
			(at 2.050034 16.575024 270)
			(size 0.519938 1.4986)
			(layers "F.Cu" "F.Mask" "F.Paste")
			(net "GND")
		)
		(pad "234" smd rect
			(at 2.050034 17.424908 270)
			(size 0.519938 1.4986)
			(layers "F.Cu" "F.Mask" "F.Paste")
			(net "M_F_CPU1_SB_CB<6>")
		)
		(pad "235" smd rect
			(at 2.050034 18.275046 270)
			(size 0.519938 1.4986)
			(layers "F.Cu" "F.Mask" "F.Paste")
			(net "GND")
		)
		(pad "236" smd rect
			(at 2.050034 19.12493 270)
			(size 0.519938 1.4986)
			(layers "F.Cu" "F.Mask" "F.Paste")
			(net "M_F_CPU1_SB_CB<7>")
		)
		(pad "237" smd rect
			(at 2.050034 19.975068 270)
			(size 0.519938 1.4986)
			(layers "F.Cu" "F.Mask" "F.Paste")
			(net "GND")
		)
		(pad "238" smd rect
			(at 2.050034 20.824952 270)
			(size 0.519938 1.4986)
			(layers "F.Cu" "F.Mask" "F.Paste")
			(net "M_F_CPU1_SB_DQS_DN<4>")
		)
		(pad "239" smd rect
			(at 2.050034 21.67509 270)
			(size 0.519938 1.4986)
			(layers "F.Cu" "F.Mask" "F.Paste")
			(net "M_F_CPU1_SB_DQS_DP<4>")
		)
		(pad "240" smd rect
			(at 2.050034 22.524974 270)
			(size 0.519938 1.4986)
			(layers "F.Cu" "F.Mask" "F.Paste")
			(net "GND")
		)
		(pad "241" smd rect
			(at 2.050034 23.375112 270)
			(size 0.519938 1.4986)
			(layers "F.Cu" "F.Mask" "F.Paste")
			(net "M_F_CPU1_SB_CB<2>")
		)
		(pad "242" smd rect
			(at 2.050034 24.224996 270)
			(size 0.519938 1.4986)
			(layers "F.Cu" "F.Mask" "F.Paste")
			(net "GND")
		)
		(pad "243" smd rect
			(at 2.050034 25.07488 270)
			(size 0.519938 1.4986)
			(layers "F.Cu" "F.Mask" "F.Paste")
			(net "M_F_CPU1_SB_CB<3>")
		)
		(pad "244" smd rect
			(at 2.050034 25.925018 270)
			(size 0.519938 1.4986)
			(layers "F.Cu" "F.Mask" "F.Paste")
			(net "GND")
		)
		(pad "245" smd rect
			(at 2.050034 26.774902 270)
			(size 0.519938 1.4986)
			(layers "F.Cu" "F.Mask" "F.Paste")
			(net "M_F_CPU1_SB_DQ<2>")
		)
		(pad "246" smd rect
			(at 2.050034 27.62504 270)
			(size 0.519938 1.4986)
			(layers "F.Cu" "F.Mask" "F.Paste")
			(net "GND")
		)
		(pad "247" smd rect
			(at 2.050034 28.474924 270)
			(size 0.519938 1.4986)
			(layers "F.Cu" "F.Mask" "F.Paste")
			(net "M_F_CPU1_SB_DQ<3>")
		)
		(pad "248" smd rect
			(at 2.050034 29.325062 270)
			(size 0.519938 1.4986)
			(layers "F.Cu" "F.Mask" "F.Paste")
			(net "GND")
		)
		(pad "249" smd rect
			(at 2.050034 30.174946 270)
			(size 0.519938 1.4986)
			(layers "F.Cu" "F.Mask" "F.Paste")
			(net "M_F_CPU1_SB_DQS_DN<5>")
		)
		(pad "250" smd rect
			(at 2.050034 31.025084 270)
			(size 0.519938 1.4986)
			(layers "F.Cu" "F.Mask" "F.Paste")
			(net "M_F_CPU1_SB_DQS_DP<5>")
		)
		(pad "251" smd rect
			(at 2.050034 31.874968 270)
			(size 0.519938 1.4986)
			(layers "F.Cu" "F.Mask" "F.Paste")
			(net "GND")
		)
		(pad "252" smd rect
			(at 2.050034 32.725106 270)
			(size 0.519938 1.4986)
			(layers "F.Cu" "F.Mask" "F.Paste")
			(net "M_F_CPU1_SB_DQ<6>")
		)
		(pad "253" smd rect
			(at 2.050034 33.57499 270)
			(size 0.519938 1.4986)
			(layers "F.Cu" "F.Mask" "F.Paste")
			(net "GND")
		)
		(pad "254" smd rect
			(at 2.050034 34.425128 270)
			(size 0.519938 1.4986)
			(layers "F.Cu" "F.Mask" "F.Paste")
			(net "M_F_CPU1_SB_DQ<7>")
		)
		(pad "255" smd rect
			(at 2.050034 35.275012 270)
			(size 0.519938 1.4986)
			(layers "F.Cu" "F.Mask" "F.Paste")
			(net "GND")
		)
		(pad "256" smd rect
			(at 2.050034 36.124896 270)
			(size 0.519938 1.4986)
			(layers "F.Cu" "F.Mask" "F.Paste")
			(net "M_F_CPU1_SB_DQ<10>")
		)
		(pad "257" smd rect
			(at 2.050034 36.975034 270)
			(size 0.519938 1.4986)
			(layers "F.Cu" "F.Mask" "F.Paste")
			(net "GND")
		)
		(pad "258" smd rect
			(at 2.050034 37.824918 270)
			(size 0.519938 1.4986)
			(layers "F.Cu" "F.Mask" "F.Paste")
			(net "M_F_CPU1_SB_DQ<11>")
		)
		(pad "259" smd rect
			(at 2.050034 38.675056 270)
			(size 0.519938 1.4986)
			(layers "F.Cu" "F.Mask" "F.Paste")
			(net "GND")
		)
		(pad "260" smd rect
			(at 2.050034 39.52494 270)
			(size 0.519938 1.4986)
			(layers "F.Cu" "F.Mask" "F.Paste")
			(net "M_F_CPU1_SB_DQS_DN<6>")
		)
		(pad "261" smd rect
			(at 2.050034 40.375078 270)
			(size 0.519938 1.4986)
			(layers "F.Cu" "F.Mask" "F.Paste")
			(net "M_F_CPU1_SB_DQS_DP<6>")
		)
		(pad "262" smd rect
			(at 2.050034 41.224962 270)
			(size 0.519938 1.4986)
			(layers "F.Cu" "F.Mask" "F.Paste")
			(net "GND")
		)
		(pad "263" smd rect
			(at 2.050034 42.0751 270)
			(size 0.519938 1.4986)
			(layers "F.Cu" "F.Mask" "F.Paste")
			(net "M_F_CPU1_SB_DQ<14>")
		)
		(pad "264" smd rect
			(at 2.050034 42.924984 270)
			(size 0.519938 1.4986)
			(layers "F.Cu" "F.Mask" "F.Paste")
			(net "GND")
		)
		(pad "265" smd rect
			(at 2.050034 43.775122 270)
			(size 0.519938 1.4986)
			(layers "F.Cu" "F.Mask" "F.Paste")
			(net "M_F_CPU1_SB_DQ<15>")
		)
		(pad "266" smd rect
			(at 2.050034 44.625006 270)
			(size 0.519938 1.4986)
			(layers "F.Cu" "F.Mask" "F.Paste")
			(net "GND")
		)
		(pad "267" smd rect
			(at 2.050034 45.47489 270)
			(size 0.519938 1.4986)
			(layers "F.Cu" "F.Mask" "F.Paste")
			(net "M_F_CPU1_SB_DQ<18>")
		)
		(pad "268" smd rect
			(at 2.050034 46.325028 270)
			(size 0.519938 1.4986)
			(layers "F.Cu" "F.Mask" "F.Paste")
			(net "GND")
		)
		(pad "269" smd rect
			(at 2.050034 47.174912 270)
			(size 0.519938 1.4986)
			(layers "F.Cu" "F.Mask" "F.Paste")
			(net "M_F_CPU1_SB_DQ<19>")
		)
		(pad "270" smd rect
			(at 2.050034 48.02505 270)
			(size 0.519938 1.4986)
			(layers "F.Cu" "F.Mask" "F.Paste")
			(net "GND")
		)
		(pad "271" smd rect
			(at 2.050034 48.874934 270)
			(size 0.519938 1.4986)
			(layers "F.Cu" "F.Mask" "F.Paste")
			(net "M_F_CPU1_SB_DQS_DN<7>")
		)
		(pad "272" smd rect
			(at 2.050034 49.725072 270)
			(size 0.519938 1.4986)
			(layers "F.Cu" "F.Mask" "F.Paste")
			(net "M_F_CPU1_SB_DQS_DP<7>")
		)
		(pad "273" smd rect
			(at 2.050034 50.574956 270)
			(size 0.519938 1.4986)
			(layers "F.Cu" "F.Mask" "F.Paste")
			(net "GND")
		)
		(pad "274" smd rect
			(at 2.050034 51.425094 270)
			(size 0.519938 1.4986)
			(layers "F.Cu" "F.Mask" "F.Paste")
			(net "M_F_CPU1_SB_DQ<22>")
		)
	)
)
